# T6G (Grand Teton) — schematic netlist excerpt (pin names and nets, part order shuffled) for the footprints in the layout excerpt that follows; sources: Cadence DE-HDL packaged netlist, KiCad conversion of 04192023_DAF0TMB3IC0_F0TG_MB_C_brd_V02_OCP.brd

R3292  Q_RES  4.7K 1% CHIP  pkg 0402LF  page 111 : A = P3V3_AUX ; B = CLK_GEN2_GPU_FPGA_OE_OR_N

J48  SCONN8_G802M0083150RD3HR  IO  pkg HEADER2X4SXN  page 27
  \1\  = CPU0_BP0
  \2\  = GND
  \3\  = CPU0_BP1
  \4\  = GND
  \5\  = CPU0_BP2
  \6\  = GND
  \7\  = CPU0_BP3
  \8\  = GND

(kicad_pcb
	(version 20260206)
	(generator "pcbnew")
	(generator_version "10.0")
	(general
		(thickness 1.6)
		(legacy_teardrops no)
	)
	(paper "A4")
	(title_block
		(title "04192023_DAF0TMB3IC0_F0TG_MB_C_brd_V02_OCP.brd")
		(comment 1 "Grand Teton / footprints 4155-4156 of 8354")
	)
	(layers
		(0 "F.Cu" signal "TOP")
		(4 "In1.Cu" signal "GND")
		(6 "In2.Cu" signal "IN1")
		(8 "In3.Cu" signal "GND1")
		(10 "In4.Cu" signal "IN2")
		(12 "In5.Cu" signal "GND2")
		(14 "In6.Cu" signal "IN3")
		(16 "In7.Cu" signal "GND3")
		(18 "In8.Cu" signal "VCC")
		(20 "In9.Cu" signal "VCC1")
		(22 "In10.Cu" signal "GND4")
		(24 "In11.Cu" signal "IN4")
		(26 "In12.Cu" signal "GND5")
		(28 "In13.Cu" signal "IN5")
		(30 "In14.Cu" signal "GND6")
		(32 "In15.Cu" signal "IN6")
		(34 "In16.Cu" signal "GND7")
		(2 "B.Cu" signal "BOTTOM")
		(9 "F.Adhes" user "F.Adhesive")
		(11 "B.Adhes" user "B.Adhesive")
		(13 "F.Paste" user "Package Geometry/Pastemask Top")
		(15 "B.Paste" user "Package Geometry/Pastemask Bottom")
		(5 "F.SilkS" user "Ref Des/Silkscreen Top")
		(7 "B.SilkS" user "Ref Des/Silkscreen Bottom")
		(1 "F.Mask" user "Board Geometry/Soldermask Top")
		(3 "B.Mask" user "Board Geometry/Soldermask Bottom")
		(17 "Dwgs.User" user "User.Drawings")
		(19 "Cmts.User" user "User.Comments")
		(21 "Eco1.User" user "User.Eco1")
		(23 "Eco2.User" user "User.Eco2")
		(25 "Edge.Cuts" user "Board Geometry/Outline")
		(27 "Margin" user)
		(31 "F.CrtYd" user "Package Geometry/Place Bound Top")
		(29 "B.CrtYd" user "Package Geometry/Place Bound Bottom")
		(35 "F.Fab" user "Ref Des/Assembly Top")
		(33 "B.Fab" user "Ref Des/Assembly Bottom")
	)
	(footprint ""
		(layer "F.Cu")
		(at 39.459662 -429.790098 90)
		(property "Reference" "R3292"
			(at 0 0 90)
			(layer "F.SilkS")
			(hide yes)
			(effects
				(font
					(size 1.27 1.27)
				)
			)
		)
		(property "Value" ""
			(at 0 0 90)
			(layer "F.Fab")
			(effects
				(font
					(size 1.27 1.27)
				)
			)
		)
		(duplicate_pad_numbers_are_jumpers no)
		(fp_line
			(start 0.7874 -0.4064)
			(end 0.7874 0.4064)
			(stroke
				(width 0.1524)
				(type default)
			)
			(layer "F.SilkS")
		)
		(fp_line
			(start -0.7874 -0.4064)
			(end 0.7874 -0.4064)
			(stroke
				(width 0.1524)
				(type default)
			)
			(layer "F.SilkS")
		)
		(fp_line
			(start 0.7874 0.4064)
			(end -0.7874 0.4064)
			(stroke
				(width 0.1524)
				(type default)
			)
			(layer "F.SilkS")
		)
		(fp_line
			(start -0.7874 0.4064)
			(end -0.7874 -0.4064)
			(stroke
				(width 0.1524)
				(type default)
			)
			(layer "F.SilkS")
		)
		(fp_line
			(start -0.12065 -0.305054)
			(end -0.12065 -0.2794)
			(stroke
				(width 0.1)
				(type default)
			)
			(layer "F.Fab")
		)
		(fp_line
			(start -0.67945 -0.305054)
			(end -0.12065 -0.305054)
			(stroke
				(width 0.1)
				(type default)
			)
			(layer "F.Fab")
		)
		(fp_line
			(start 0.67945 -0.3048)
			(end 0.67945 0.3048)
			(stroke
				(width 0.1)
				(type default)
			)
			(layer "F.Fab")
		)
		(fp_line
			(start 0.12065 -0.3048)
			(end 0.67945 -0.3048)
			(stroke
				(width 0.1)
				(type default)
			)
			(layer "F.Fab")
		)
		(fp_line
			(start 0.12065 -0.2794)
			(end 0.12065 -0.3048)
			(stroke
				(width 0.1)
				(type default)
			)
			(layer "F.Fab")
		)
		(fp_line
			(start -0.12065 -0.2794)
			(end 0.12065 -0.2794)
			(stroke
				(width 0.1)
				(type default)
			)
			(layer "F.Fab")
		)
		(fp_line
			(start 0.120396 0.2794)
			(end -0.12065 0.2794)
			(stroke
				(width 0.1)
				(type default)
			)
			(layer "F.Fab")
		)
		(fp_line
			(start -0.12065 0.2794)
			(end -0.12065 0.3048)
			(stroke
				(width 0.1)
				(type default)
			)
			(layer "F.Fab")
		)
		(fp_line
			(start 0.67945 0.3048)
			(end 0.120396 0.3048)
			(stroke
				(width 0.1)
				(type default)
			)
			(layer "F.Fab")
		)
		(fp_line
			(start 0.120396 0.3048)
			(end 0.120396 0.2794)
			(stroke
				(width 0.1)
				(type default)
			)
			(layer "F.Fab")
		)
		(fp_line
			(start -0.12065 0.3048)
			(end -0.67945 0.3048)
			(stroke
				(width 0.1)
				(type default)
			)
			(layer "F.Fab")
		)
		(fp_line
			(start -0.67945 0.3048)
			(end -0.67945 -0.305054)
			(stroke
				(width 0.1)
				(type default)
			)
			(layer "F.Fab")
		)
		(pad "1" smd circle
			(at -0.40005 0 90)
			(size 0 0)
			(layers "F.Cu" "F.Mask" "F.Paste")
			(net "P3V3_AUX")
		)
		(pad "2" smd circle
			(at 0.40005 0 90)
			(size 0 0)
			(layers "F.Cu" "F.Mask" "F.Paste")
			(net "CLK_GEN2_GPU_FPGA_OE_OR_N")
		)
	)
	(footprint ""
		(layer "F.Cu")
		(at 320.900044 -61.999876)
		(property "Reference" "J48"
			(at 5.08 1.965452 0)
			(unlocked yes)
			(layer "F.SilkS")
			(effects
				(font
					(size 0.7874 0.5842)
					(thickness 0.1524)
				)
			)
		)
		(property "Value" ""
			(at 0 0 0)
			(layer "F.Fab")
			(effects
				(font
					(size 1.27 1.27)
				)
			)
		)
		(duplicate_pad_numbers_are_jumpers no)
		(fp_line
			(start -1.700022 -2.739898)
			(end 1.700022 -2.739898)
			(stroke
				(width 0.1524)
				(type default)
			)
			(layer "F.SilkS")
		)
		(fp_line
			(start -1.700022 -2.4257)
			(end -1.700022 -2.739898)
			(stroke
				(width 0.1524)
				(type default)
			)
			(layer "F.SilkS")
		)
		(fp_line
			(start -1.700022 -1.1557)
			(end -1.700022 -1.3843)
			(stroke
				(width 0.1524)
				(type default)
			)
			(layer "F.SilkS")
		)
		(fp_line
			(start -1.700022 0.1143)
			(end -1.700022 -0.1143)
			(stroke
				(width 0.1524)
				(type default)
			)
			(layer "F.SilkS")
		)
		(fp_line
			(start -1.700022 1.3843)
			(end -1.700022 1.1557)
			(stroke
				(width 0.1524)
				(type default)
			)
			(layer "F.SilkS")
		)
		(fp_line
			(start -1.700022 2.739898)
			(end -1.700022 2.4257)
			(stroke
				(width 0.1524)
				(type default)
			)
			(layer "F.SilkS")
		)
		(fp_line
			(start 1.700022 -2.739898)
			(end 1.700022 -2.4257)
			(stroke
				(width 0.1524)
				(type default)
			)
			(layer "F.SilkS")
		)
		(fp_line
			(start 1.700022 -1.3843)
			(end 1.700022 -1.1557)
			(stroke
				(width 0.1524)
				(type default)
			)
			(layer "F.SilkS")
		)
		(fp_line
			(start 1.700022 -0.1143)
			(end 1.700022 0.1143)
			(stroke
				(width 0.1524)
				(type default)
			)
			(layer "F.SilkS")
		)
		(fp_line
			(start 1.700022 1.1557)
			(end 1.700022 1.3843)
			(stroke
				(width 0.1524)
				(type default)
			)
			(layer "F.SilkS")
		)
		(fp_line
			(start 1.700022 2.4257)
			(end 1.700022 2.739898)
			(stroke
				(width 0.1524)
				(type default)
			)
			(layer "F.SilkS")
		)
		(fp_line
			(start 1.700022 2.739898)
			(end -1.700022 2.739898)
			(stroke
				(width 0.1524)
				(type default)
			)
			(layer "F.SilkS")
		)
		(fp_poly
			(pts
				(xy -3.383534 -1.905) (xy -4.399534 -1.397) (xy -4.399534 -2.413)
			)
			(stroke
				(width 0)
				(type default)
			)
			(fill yes)
			(layer "F.SilkS")
		)
		(fp_line
			(start -1.700022 -2.739898)
			(end 1.700022 -2.739898)
			(stroke
				(width 0.1)
				(type default)
			)
			(layer "F.Fab")
		)
		(fp_line
			(start -1.700022 2.739898)
			(end -1.700022 -2.739898)
			(stroke
				(width 0.1)
				(type default)
			)
			(layer "F.Fab")
		)
		(fp_line
			(start 1.700022 -2.739898)
			(end 1.700022 2.739898)
			(stroke
				(width 0.1)
				(type default)
			)
			(layer "F.Fab")
		)
		(fp_line
			(start 1.700022 2.739898)
			(end -1.700022 2.739898)
			(stroke
				(width 0.1)
				(type default)
			)
			(layer "F.Fab")
		)
		(fp_poly
			(pts
				(xy -4.399534 -2.413) (xy -4.399534 -1.397) (xy -3.383534 -1.905)
			)
			(stroke
				(width 0)
				(type default)
			)
			(fill yes)
			(layer "F.Fab")
		)
		(pad "1" smd rect
			(at -2.050034 -1.905 270)
			(size 0.762 2.413)
			(layers "F.Cu" "F.Mask" "F.Paste")
			(net "CPU0_BP0")
		)
		(pad "2" smd rect
			(at 2.050034 -1.905 270)
			(size 0.762 2.413)
			(layers "F.Cu" "F.Mask" "F.Paste")
			(net "GND")
		)
		(pad "3" smd rect
			(at -2.050034 -0.635 270)
			(size 0.762 2.413)
			(layers "F.Cu" "F.Mask" "F.Paste")
			(net "CPU0_BP1")
		)
		(pad "4" smd rect
			(at 2.050034 -0.635 270)
			(size 0.762 2.413)
			(layers "F.Cu" "F.Mask" "F.Paste")
			(net "GND")
		)
		(pad "5" smd rect
			(at -2.050034 0.635 270)
			(size 0.762 2.413)
			(layers "F.Cu" "F.Mask" "F.Paste")
			(net "CPU0_BP2")
		)
		(pad "6" smd rect
			(at 2.050034 0.635 270)
			(size 0.762 2.413)
			(layers "F.Cu" "F.Mask" "F.Paste")
			(net "GND")
		)
		(pad "7" smd rect
			(at -2.050034 1.905 270)
			(size 0.762 2.413)
			(layers "F.Cu" "F.Mask" "F.Paste")
			(net "CPU0_BP3")
		)
		(pad "8" smd rect
			(at 2.050034 1.905 270)
			(size 0.762 2.413)
			(layers "F.Cu" "F.Mask" "F.Paste")
			(net "GND")
		)
	)
)
